(kicad_sch (version 20230121) (generator eeschema)

  (paper "A4")

  (title_block
    (title "ECP5 - Datacenter Secure Control Module (DC-SCM)")
    (date "2024-07-15")
    (rev "1.2.1")
  )

  (junction (at 119.38 63.5) (diameter 0) (color 0 0 0 0)
  )
  (junction (at 121.92 66.04) (diameter 0) (color 0 0 0 0)
  )
  (junction (at 127 63.5) (diameter 0) (color 0 0 0 0)
  )
  (junction (at 173.99 140.97) (diameter 0) (color 0 0 0 0)
  )

  (no_connect (at 172.72 95.25))
  (no_connect (at 172.72 76.2))
  (no_connect (at 172.72 92.71))
  (no_connect (at 193.04 140.97))

  (wire (pts (xy 129.54 130.81) (xy 114.3 130.81))
    (stroke (width 0) (type default))
  )
  (wire (pts (xy 114.3 123.19) (xy 142.24 123.19))
    (stroke (width 0) (type default))
  )
  (wire (pts (xy 116.84 68.58) (xy 142.24 68.58))
    (stroke (width 0) (type default))
  )
  (wire (pts (xy 121.92 102.87) (xy 114.3 102.87))
    (stroke (width 0) (type default))
  )
  (wire (pts (xy 114.3 125.73) (xy 142.24 125.73))
    (stroke (width 0) (type default))
  )
  (wire (pts (xy 121.92 57.15) (xy 121.92 66.04))
    (stroke (width 0) (type default))
  )
  (wire (pts (xy 127 57.15) (xy 127 63.5))
    (stroke (width 0) (type default))
  )
  (wire (pts (xy 175.26 118.11) (xy 172.72 118.11))
    (stroke (width 0) (type default))
  )
  (wire (pts (xy 127 63.5) (xy 142.24 63.5))
    (stroke (width 0) (type default))
  )
  (wire (pts (xy 231.14 67.31) (xy 231.14 68.58))
    (stroke (width 0) (type default))
  )
  (wire (pts (xy 116.84 66.04) (xy 121.92 66.04))
    (stroke (width 0) (type default))
  )
  (wire (pts (xy 119.38 63.5) (xy 127 63.5))
    (stroke (width 0) (type default))
  )
  (wire (pts (xy 222.25 60.96) (xy 222.25 62.23))
    (stroke (width 0) (type default))
  )
  (wire (pts (xy 142.24 102.87) (xy 127 102.87))
    (stroke (width 0) (type default))
  )
  (wire (pts (xy 119.38 62.23) (xy 119.38 63.5))
    (stroke (width 0) (type default))
  )
  (wire (pts (xy 121.92 118.11) (xy 114.3 118.11))
    (stroke (width 0) (type default))
  )
  (wire (pts (xy 180.34 90.17) (xy 184.15 90.17))
    (stroke (width 0) (type default))
  )
  (wire (pts (xy 173.99 140.97) (xy 173.99 143.51))
    (stroke (width 0) (type default))
  )
  (wire (pts (xy 142.24 100.33) (xy 134.62 100.33))
    (stroke (width 0) (type default))
  )
  (wire (pts (xy 142.24 115.57) (xy 134.62 115.57))
    (stroke (width 0) (type default))
  )
  (wire (pts (xy 172.72 138.43) (xy 173.99 138.43))
    (stroke (width 0) (type default))
  )
  (wire (pts (xy 190.5 118.11) (xy 187.96 118.11))
    (stroke (width 0) (type default))
  )
  (wire (pts (xy 114.3 76.2) (xy 142.24 76.2))
    (stroke (width 0) (type default))
  )
  (wire (pts (xy 114.3 110.49) (xy 142.24 110.49))
    (stroke (width 0) (type default))
  )
  (wire (pts (xy 204.47 67.31) (xy 204.47 68.58))
    (stroke (width 0) (type default))
  )
  (wire (pts (xy 142.24 133.35) (xy 127 133.35))
    (stroke (width 0) (type default))
  )
  (wire (pts (xy 142.24 118.11) (xy 127 118.11))
    (stroke (width 0) (type default))
  )
  (wire (pts (xy 127 49.53) (xy 127 52.07))
    (stroke (width 0) (type default))
  )
  (wire (pts (xy 129.54 85.09) (xy 114.3 85.09))
    (stroke (width 0) (type default))
  )
  (wire (pts (xy 142.24 85.09) (xy 134.62 85.09))
    (stroke (width 0) (type default))
  )
  (wire (pts (xy 114.3 107.95) (xy 142.24 107.95))
    (stroke (width 0) (type default))
  )
  (wire (pts (xy 142.24 87.63) (xy 127 87.63))
    (stroke (width 0) (type default))
  )
  (wire (pts (xy 114.3 140.97) (xy 142.24 140.97))
    (stroke (width 0) (type default))
  )
  (wire (pts (xy 121.92 66.04) (xy 142.24 66.04))
    (stroke (width 0) (type default))
  )
  (wire (pts (xy 172.72 90.17) (xy 175.26 90.17))
    (stroke (width 0) (type default))
  )
  (wire (pts (xy 114.3 138.43) (xy 142.24 138.43))
    (stroke (width 0) (type default))
  )
  (wire (pts (xy 213.36 67.31) (xy 213.36 68.58))
    (stroke (width 0) (type default))
  )
  (wire (pts (xy 114.3 78.74) (xy 142.24 78.74))
    (stroke (width 0) (type default))
  )
  (wire (pts (xy 204.47 60.96) (xy 204.47 62.23))
    (stroke (width 0) (type default))
  )
  (wire (pts (xy 114.3 95.25) (xy 142.24 95.25))
    (stroke (width 0) (type default))
  )
  (wire (pts (xy 121.92 133.35) (xy 114.3 133.35))
    (stroke (width 0) (type default))
  )
  (wire (pts (xy 213.36 60.96) (xy 213.36 62.23))
    (stroke (width 0) (type default))
  )
  (wire (pts (xy 172.72 63.5) (xy 177.8 63.5))
    (stroke (width 0) (type default))
  )
  (wire (pts (xy 121.92 49.53) (xy 121.92 52.07))
    (stroke (width 0) (type default))
  )
  (wire (pts (xy 142.24 130.81) (xy 134.62 130.81))
    (stroke (width 0) (type default))
  )
  (wire (pts (xy 118.11 63.5) (xy 119.38 63.5))
    (stroke (width 0) (type default))
  )
  (wire (pts (xy 172.72 140.97) (xy 173.99 140.97))
    (stroke (width 0) (type default))
  )
  (wire (pts (xy 121.92 87.63) (xy 114.3 87.63))
    (stroke (width 0) (type default))
  )
  (wire (pts (xy 129.54 100.33) (xy 114.3 100.33))
    (stroke (width 0) (type default))
  )
  (wire (pts (xy 173.99 138.43) (xy 173.99 140.97))
    (stroke (width 0) (type default))
  )
  (wire (pts (xy 231.14 60.96) (xy 231.14 62.23))
    (stroke (width 0) (type default))
  )
  (wire (pts (xy 114.3 92.71) (xy 142.24 92.71))
    (stroke (width 0) (type default))
  )
  (wire (pts (xy 129.54 115.57) (xy 114.3 115.57))
    (stroke (width 0) (type default))
  )
  (wire (pts (xy 222.25 67.31) (xy 222.25 68.58))
    (stroke (width 0) (type default))
  )
  (wire (pts (xy 182.88 118.11) (xy 180.34 118.11))
    (stroke (width 0) (type default))
  )

  (global_label "VCC3V3" (shape input) (at 177.8 63.5 0) (fields_autoplaced)
    (effects (font (size 1.27 1.27)) (justify left))
    (property "Intersheetrefs" "${INTERSHEET_REFS}" (at 187.2672 63.5 0)
      (effects (font (size 1.27 1.27)) (justify left) hide)
    )
  )
  (global_label "PCIE_HPM_RX3_N" (shape input) (at 114.3 140.97 180) (fields_autoplaced)
    (effects (font (size 1.27 1.27)) (justify right))
    (property "Intersheetrefs" "${INTERSHEET_REFS}" (at 286.385 15.24 0)
      (effects (font (size 1.27 1.27)) hide)
    )
  )
  (global_label "VCC3V3" (shape input) (at 190.5 118.11 0) (fields_autoplaced)
    (effects (font (size 1.27 1.27)) (justify left))
    (property "Intersheetrefs" "${INTERSHEET_REFS}" (at 199.9672 118.11 0)
      (effects (font (size 1.27 1.27)) (justify left) hide)
    )
  )
  (global_label "CLK_PCIE_x4_DP" (shape input) (at 114.3 76.2 180) (fields_autoplaced)
    (effects (font (size 1.27 1.27)) (justify right))
    (property "Intersheetrefs" "${INTERSHEET_REFS}" (at 286.385 13.97 0)
      (effects (font (size 1.27 1.27)) hide)
    )
  )
  (global_label "PCIE_HPM_RX0_P" (shape input) (at 114.3 92.71 180) (fields_autoplaced)
    (effects (font (size 1.27 1.27)) (justify right))
    (property "Intersheetrefs" "${INTERSHEET_REFS}" (at 286.385 15.24 0)
      (effects (font (size 1.27 1.27)) hide)
    )
  )
  (global_label "VCC3V3" (shape input) (at 213.36 60.96 90) (fields_autoplaced)
    (effects (font (size 1.27 1.27)) (justify left))
    (property "Intersheetrefs" "${INTERSHEET_REFS}" (at -17.145 -85.09 0)
      (effects (font (size 1.27 1.27)) hide)
    )
  )
  (global_label "VCC3V3" (shape input) (at 231.14 60.96 90) (fields_autoplaced)
    (effects (font (size 1.27 1.27)) (justify left))
    (property "Intersheetrefs" "${INTERSHEET_REFS}" (at -17.145 -85.09 0)
      (effects (font (size 1.27 1.27)) hide)
    )
  )
  (global_label "PCIE_HPM_TX1_P" (shape input) (at 114.3 100.33 180) (fields_autoplaced)
    (effects (font (size 1.27 1.27)) (justify right))
    (property "Intersheetrefs" "${INTERSHEET_REFS}" (at 300.99 15.24 0)
      (effects (font (size 1.27 1.27)) hide)
    )
  )
  (global_label "PCIE_HPM_RX2_N" (shape input) (at 114.3 125.73 180) (fields_autoplaced)
    (effects (font (size 1.27 1.27)) (justify right))
    (property "Intersheetrefs" "${INTERSHEET_REFS}" (at 286.385 15.24 0)
      (effects (font (size 1.27 1.27)) hide)
    )
  )
  (global_label "VCC3V3" (shape input) (at 222.25 60.96 90) (fields_autoplaced)
    (effects (font (size 1.27 1.27)) (justify left))
    (property "Intersheetrefs" "${INTERSHEET_REFS}" (at -17.145 -85.09 0)
      (effects (font (size 1.27 1.27)) hide)
    )
  )
  (global_label "PCIE_HPM_TX3_N" (shape input) (at 114.3 133.35 180) (fields_autoplaced)
    (effects (font (size 1.27 1.27)) (justify right))
    (property "Intersheetrefs" "${INTERSHEET_REFS}" (at 300.99 15.24 0)
      (effects (font (size 1.27 1.27)) hide)
    )
  )
  (global_label "PCIE_HPM_TX2_N" (shape input) (at 114.3 118.11 180) (fields_autoplaced)
    (effects (font (size 1.27 1.27)) (justify right))
    (property "Intersheetrefs" "${INTERSHEET_REFS}" (at 300.99 15.24 0)
      (effects (font (size 1.27 1.27)) hide)
    )
  )
  (global_label "PCIE_HPM_RX3_P" (shape input) (at 114.3 138.43 180) (fields_autoplaced)
    (effects (font (size 1.27 1.27)) (justify right))
    (property "Intersheetrefs" "${INTERSHEET_REFS}" (at 286.385 15.24 0)
      (effects (font (size 1.27 1.27)) hide)
    )
  )
  (global_label "PCIE_HPM_RX1_P" (shape input) (at 114.3 107.95 180) (fields_autoplaced)
    (effects (font (size 1.27 1.27)) (justify right))
    (property "Intersheetrefs" "${INTERSHEET_REFS}" (at 286.385 15.24 0)
      (effects (font (size 1.27 1.27)) hide)
    )
  )
  (global_label "VCC1V8" (shape input) (at 184.15 90.17 0) (fields_autoplaced)
    (effects (font (size 1.27 1.27)) (justify left))
    (property "Intersheetrefs" "${INTERSHEET_REFS}" (at 193.6172 90.17 0)
      (effects (font (size 1.27 1.27)) (justify left) hide)
    )
  )
  (global_label "PCIE_HPM_TX2_P" (shape input) (at 114.3 115.57 180) (fields_autoplaced)
    (effects (font (size 1.27 1.27)) (justify right))
    (property "Intersheetrefs" "${INTERSHEET_REFS}" (at 300.99 15.24 0)
      (effects (font (size 1.27 1.27)) hide)
    )
  )
  (global_label "PCIE_HPM_TX3_P" (shape input) (at 114.3 130.81 180) (fields_autoplaced)
    (effects (font (size 1.27 1.27)) (justify right))
    (property "Intersheetrefs" "${INTERSHEET_REFS}" (at 300.99 15.24 0)
      (effects (font (size 1.27 1.27)) hide)
    )
  )
  (global_label "CLK_PCIE_x4_DN" (shape input) (at 114.3 78.74 180) (fields_autoplaced)
    (effects (font (size 1.27 1.27)) (justify right))
    (property "Intersheetrefs" "${INTERSHEET_REFS}" (at 286.385 13.97 0)
      (effects (font (size 1.27 1.27)) hide)
    )
  )
  (global_label "PCIE_HPM_RX2_P" (shape input) (at 114.3 123.19 180) (fields_autoplaced)
    (effects (font (size 1.27 1.27)) (justify right))
    (property "Intersheetrefs" "${INTERSHEET_REFS}" (at 286.385 15.24 0)
      (effects (font (size 1.27 1.27)) hide)
    )
  )
  (global_label "VCC3V3" (shape input) (at 204.47 60.96 90) (fields_autoplaced)
    (effects (font (size 1.27 1.27)) (justify left))
    (property "Intersheetrefs" "${INTERSHEET_REFS}" (at -17.145 -85.09 0)
      (effects (font (size 1.27 1.27)) hide)
    )
  )
  (global_label "PRSNT0_N" (shape input) (at 118.11 63.5 180) (fields_autoplaced)
    (effects (font (size 1.27 1.27)) (justify right))
    (property "Intersheetrefs" "${INTERSHEET_REFS}" (at 24.765 -6.35 0)
      (effects (font (size 1.27 1.27)) hide)
    )
  )
  (global_label "PCIE_HPM_RX1_N" (shape input) (at 114.3 110.49 180) (fields_autoplaced)
    (effects (font (size 1.27 1.27)) (justify right))
    (property "Intersheetrefs" "${INTERSHEET_REFS}" (at 286.385 15.24 0)
      (effects (font (size 1.27 1.27)) hide)
    )
  )
  (global_label "PCIE_HPM_TX1_N" (shape input) (at 114.3 102.87 180) (fields_autoplaced)
    (effects (font (size 1.27 1.27)) (justify right))
    (property "Intersheetrefs" "${INTERSHEET_REFS}" (at 300.99 15.24 0)
      (effects (font (size 1.27 1.27)) hide)
    )
  )
  (global_label "VCC3V3" (shape input) (at 127 49.53 90) (fields_autoplaced)
    (effects (font (size 1.27 1.27)) (justify left))
    (property "Intersheetrefs" "${INTERSHEET_REFS}" (at 29.845 11.43 0)
      (effects (font (size 1.27 1.27)) hide)
    )
  )
  (global_label "VCC3V3" (shape input) (at 121.92 49.53 90) (fields_autoplaced)
    (effects (font (size 1.27 1.27)) (justify left))
    (property "Intersheetrefs" "${INTERSHEET_REFS}" (at 24.765 11.43 0)
      (effects (font (size 1.27 1.27)) hide)
    )
  )
  (global_label "PCIE_HPM_TX0_P" (shape input) (at 114.3 85.09 180) (fields_autoplaced)
    (effects (font (size 1.27 1.27)) (justify right))
    (property "Intersheetrefs" "${INTERSHEET_REFS}" (at 300.99 15.24 0)
      (effects (font (size 1.27 1.27)) hide)
    )
  )
  (global_label "PCIE_HPM_RX0_N" (shape input) (at 114.3 95.25 180) (fields_autoplaced)
    (effects (font (size 1.27 1.27)) (justify right))
    (property "Intersheetrefs" "${INTERSHEET_REFS}" (at 286.385 15.24 0)
      (effects (font (size 1.27 1.27)) hide)
    )
  )
  (global_label "PCIE_HPM_TX0_N" (shape input) (at 114.3 87.63 180) (fields_autoplaced)
    (effects (font (size 1.27 1.27)) (justify right))
    (property "Intersheetrefs" "${INTERSHEET_REFS}" (at 300.99 15.24 0)
      (effects (font (size 1.27 1.27)) hide)
    )
  )

  (symbol (lib_id "antmicroCapacitors0402:C_100n_0402") (at 134.62 85.09 180) (unit 1)
    (in_bom yes) (on_board yes) (dnp no)
    (property "Reference" "C31" (at 135.89 83.82 0)
      (effects (font (size 1.524 1.524)))
    )
    (property "Value" "C_100n_0402" (at 134.62 81.28 0)
      (effects (font (size 1.524 1.524)) hide)
    )
    (property "Footprint" "antmicro-footprints:C_0402_1005Metric" (at 129.54 90.17 0)
      (effects (font (size 1.524 1.524)) (justify left) hide)
    )
    (property "Datasheet" "https://www.murata.com/products/productdetail?partno=GRM155R61H104KE14%23" (at 134.62 85.09 0)
      (effects (font (size 1.27 1.27)) hide)
    )
    (property "Manufacturer" "Murata" (at 129.54 95.25 0)
      (effects (font (size 1.524 1.524)) (justify left) hide)
    )
    (property "MPN" "GRM155R61H104KE14D" (at 129.54 92.71 0)
      (effects (font (size 1.524 1.524)) (justify left) hide)
    )
    (property "Val" "100n" (at 128.27 83.82 0)
      (effects (font (size 1.27 1.27)))
    )
    (property "License" "Apache-2.0" (at 114.3 62.23 0)
      (effects (font (size 1.27 1.27) (thickness 0.15)) (justify left bottom) hide)
    )
    (property "Author" "Antmicro" (at 114.3 59.69 0)
      (effects (font (size 1.27 1.27) (thickness 0.15)) (justify left bottom) hide)
    )
    (property "Voltage" "50V" (at 114.3 57.15 0)
      (effects (font (size 1.27 1.27)) (justify left bottom) hide)
    )
    (property "Dielectric" "X5R" (at 114.3 54.61 0)
      (effects (font (size 1.27 1.27)) (justify left bottom) hide)
    )
    (property "Public" "False" (at 114.3 52.07 0)
      (effects (font (size 1.27 1.27)) (justify left bottom) hide)
    )
    (pin "1")
    (pin "2")
    (instances
      (project "ecp5-dc-scm"
        (path ""
          (reference "C31") (unit 1)
        )
      )
    )
  )

  (symbol (lib_id "antmicroCapacitors0402:C_100n_0402") (at 127 87.63 180) (unit 1)
    (in_bom yes) (on_board yes) (dnp no)
    (property "Reference" "C35" (at 128.27 88.9 0)
      (effects (font (size 1.524 1.524)))
    )
    (property "Value" "C_100n_0402" (at 127 83.82 0)
      (effects (font (size 1.524 1.524)) hide)
    )
    (property "Footprint" "antmicro-footprints:C_0402_1005Metric" (at 121.92 92.71 0)
      (effects (font (size 1.524 1.524)) (justify left) hide)
    )
    (property "Datasheet" "https://www.murata.com/products/productdetail?partno=GRM155R61H104KE14%23" (at 127 87.63 0)
      (effects (font (size 1.27 1.27)) hide)
    )
    (property "Manufacturer" "Murata" (at 121.92 97.79 0)
      (effects (font (size 1.524 1.524)) (justify left) hide)
    )
    (property "MPN" "GRM155R61H104KE14D" (at 121.92 95.25 0)
      (effects (font (size 1.524 1.524)) (justify left) hide)
    )
    (property "Val" "100n" (at 120.65 88.9 0)
      (effects (font (size 1.27 1.27)))
    )
    (property "License" "Apache-2.0" (at 106.68 64.77 0)
      (effects (font (size 1.27 1.27) (thickness 0.15)) (justify left bottom) hide)
    )
    (property "Author" "Antmicro" (at 106.68 62.23 0)
      (effects (font (size 1.27 1.27) (thickness 0.15)) (justify left bottom) hide)
    )
    (property "Voltage" "50V" (at 106.68 59.69 0)
      (effects (font (size 1.27 1.27)) (justify left bottom) hide)
    )
    (property "Dielectric" "X5R" (at 106.68 57.15 0)
      (effects (font (size 1.27 1.27)) (justify left bottom) hide)
    )
    (property "Public" "False" (at 106.68 54.61 0)
      (effects (font (size 1.27 1.27)) (justify left bottom) hide)
    )
    (pin "1")
    (pin "2")
    (instances
      (project "ecp5-dc-scm"
        (path ""
          (reference "C35") (unit 1)
        )
      )
    )
  )

  (symbol (lib_id "antmicroCapacitors0402:C_100n_0402") (at 134.62 100.33 180) (unit 1)
    (in_bom yes) (on_board yes) (dnp no)
    (property "Reference" "C32" (at 135.89 99.06 0)
      (effects (font (size 1.524 1.524)))
    )
    (property "Value" "C_100n_0402" (at 134.62 96.52 0)
      (effects (font (size 1.524 1.524)) hide)
    )
    (property "Footprint" "antmicro-footprints:C_0402_1005Metric" (at 129.54 105.41 0)
      (effects (font (size 1.524 1.524)) (justify left) hide)
    )
    (property "Datasheet" "https://www.murata.com/products/productdetail?partno=GRM155R61H104KE14%23" (at 134.62 100.33 0)
      (effects (font (size 1.27 1.27)) hide)
    )
    (property "Manufacturer" "Murata" (at 129.54 110.49 0)
      (effects (font (size 1.524 1.524)) (justify left) hide)
    )
    (property "MPN" "GRM155R61H104KE14D" (at 129.54 107.95 0)
      (effects (font (size 1.524 1.524)) (justify left) hide)
    )
    (property "Val" "100n" (at 128.27 99.06 0)
      (effects (font (size 1.27 1.27)))
    )
    (property "License" "Apache-2.0" (at 114.3 77.47 0)
      (effects (font (size 1.27 1.27) (thickness 0.15)) (justify left bottom) hide)
    )
    (property "Author" "Antmicro" (at 114.3 74.93 0)
      (effects (font (size 1.27 1.27) (thickness 0.15)) (justify left bottom) hide)
    )
    (property "Voltage" "50V" (at 114.3 72.39 0)
      (effects (font (size 1.27 1.27)) (justify left bottom) hide)
    )
    (property "Dielectric" "X5R" (at 114.3 69.85 0)
      (effects (font (size 1.27 1.27)) (justify left bottom) hide)
    )
    (property "Public" "False" (at 114.3 67.31 0)
      (effects (font (size 1.27 1.27)) (justify left bottom) hide)
    )
    (pin "1")
    (pin "2")
    (instances
      (project "ecp5-dc-scm"
        (path ""
          (reference "C32") (unit 1)
        )
      )
    )
  )

  (symbol (lib_id "antmicroCapacitors0402:C_100n_0402") (at 127 102.87 180) (unit 1)
    (in_bom yes) (on_board yes) (dnp no)
    (property "Reference" "C36" (at 128.27 104.14 0)
      (effects (font (size 1.524 1.524)))
    )
    (property "Value" "C_100n_0402" (at 127 99.06 0)
      (effects (font (size 1.524 1.524)) hide)
    )
    (property "Footprint" "antmicro-footprints:C_0402_1005Metric" (at 121.92 107.95 0)
      (effects (font (size 1.524 1.524)) (justify left) hide)
    )
    (property "Datasheet" "https://www.murata.com/products/productdetail?partno=GRM155R61H104KE14%23" (at 127 102.87 0)
      (effects (font (size 1.27 1.27)) hide)
    )
    (property "Manufacturer" "Murata" (at 121.92 113.03 0)
      (effects (font (size 1.524 1.524)) (justify left) hide)
    )
    (property "MPN" "GRM155R61H104KE14D" (at 121.92 110.49 0)
      (effects (font (size 1.524 1.524)) (justify left) hide)
    )
    (property "Val" "100n" (at 120.65 104.14 0)
      (effects (font (size 1.27 1.27)))
    )
    (property "License" "Apache-2.0" (at 106.68 80.01 0)
      (effects (font (size 1.27 1.27) (thickness 0.15)) (justify left bottom) hide)
    )
    (property "Author" "Antmicro" (at 106.68 77.47 0)
      (effects (font (size 1.27 1.27) (thickness 0.15)) (justify left bottom) hide)
    )
    (property "Voltage" "50V" (at 106.68 74.93 0)
      (effects (font (size 1.27 1.27)) (justify left bottom) hide)
    )
    (property "Dielectric" "X5R" (at 106.68 72.39 0)
      (effects (font (size 1.27 1.27)) (justify left bottom) hide)
    )
    (property "Public" "False" (at 106.68 69.85 0)
      (effects (font (size 1.27 1.27)) (justify left bottom) hide)
    )
    (pin "1")
    (pin "2")
    (instances
      (project "ecp5-dc-scm"
        (path ""
          (reference "C36") (unit 1)
        )
      )
    )
  )

  (symbol (lib_id "antmicroPciConnectors:Bus_M.2_1-2199230-6") (at 142.24 63.5 0) (unit 1)
    (in_bom yes) (on_board yes) (dnp no) (fields_autoplaced)
    (property "Reference" "J2" (at 157.48 53.34 0)
      (effects (font (size 1.524 1.524)))
    )
    (property "Value" "Bus_M.2_1-2199230-6" (at 138.43 106.68 0)
      (effects (font (size 1.524 1.524)) hide)
    )
    (property "Footprint" "antmicro-footprints:Bus_M.2_Socket_Key_M_TE_1-2199230-6" (at 138.43 106.68 0)
      (effects (font (size 1.524 1.524)) hide)
    )
    (property "Datasheet" "https://www.te.com/commerce/DocumentDelivery/DDEController?Action=srchrtrv&DocNm=2199230&DocType=Customer+Drawing&DocLang=English" (at 138.43 63.5 0)
      (effects (font (size 1.524 1.524)) hide)
    )
    (property "Manufacturer" "TE Connectivity" (at 157.48 55.88 0)
      (effects (font (size 1.27 1.27)))
    )
    (property "MPN" "1-2199230-6" (at 157.48 58.42 0)
      (effects (font (size 1.27 1.27)))
    )
    (property "Author" "Antmicro" (at 187.96 81.28 0)
      (effects (font (size 1.27 1.27) (thickness 0.15)) (justify left bottom) hide)
    )
    (property "License" "Apache-2.0" (at 187.96 83.82 0)
      (effects (font (size 1.27 1.27) (thickness 0.15)) (justify left bottom) hide)
    )
    (pin "1")
    (pin "10")
    (pin "11")
    (pin "12")
    (pin "13")
    (pin "14")
    (pin "15")
    (pin "16")
    (pin "17")
    (pin "18")
    (pin "19")
    (pin "2")
    (pin "20")
    (pin "21")
    (pin "22")
    (pin "23")
    (pin "24")
    (pin "25")
    (pin "26")
    (pin "27")
    (pin "28")
    (pin "29")
    (pin "3")
    (pin "30")
    (pin "31")
    (pin "32")
    (pin "33")
    (pin "34")
    (pin "35")
    (pin "36")
    (pin "37")
    (pin "38")
    (pin "39")
    (pin "4")
    (pin "40")
    (pin "41")
    (pin "42")
    (pin "43")
    (pin "44")
    (pin "45")
    (pin "46")
    (pin "47")
    (pin "48")
    (pin "49")
    (pin "5")
    (pin "50")
    (pin "51")
    (pin "52")
    (pin "53")
    (pin "54")
    (pin "55")
    (pin "56")
    (pin "57")
    (pin "58")
    (pin "6")
    (pin "67")
    (pin "68")
    (pin "69")
    (pin "7")
    (pin "70")
    (pin "71")
    (pin "72")
    (pin "73")
    (pin "74")
    (pin "75")
    (pin "8")
    (pin "9")
    (pin "MP1")
    (pin "MP2")
    (instances
      (project "ecp5-dc-scm"
        (path ""
          (reference "J2") (unit 1)
        )
      )
    )
  )

  (symbol (lib_id "antmicroResistors0402:R_10k_0402") (at 121.92 52.07 270) (unit 1)
    (in_bom yes) (on_board yes) (dnp no) (fields_autoplaced)
    (property "Reference" "R17" (at 119.38 53.34 90)
      (effects (font (size 1.524 1.524)) (justify right))
    )
    (property "Value" "R_10k_0402" (at 118.11 52.07 0)
      (effects (font (size 1.524 1.524)) hide)
    )
    (property "Footprint" "antmicro-footprints:R_0402_1005Metric" (at 127 57.15 0)
      (effects (font (size 1.524 1.524)) (justify left) hide)
    )
    (property "Datasheet" "https://www.bourns.com/docs/product-datasheets/cr.pdf" (at 121.92 52.07 0)
      (effects (font (size 1.27 1.27)) hide)
    )
    (property "Manufacturer" "Bourns" (at 132.08 57.15 0)
      (effects (font (size 1.524 1.524)) (justify left) hide)
    )
    (property "MPN" "CR0402-FX-1002GLF" (at 129.54 57.15 0)
      (effects (font (size 1.524 1.524)) (justify left) hide)
    )
    (property "Val" "10k" (at 119.38 55.88 90)
      (effects (font (size 1.27 1.27)) (justify right))
    )
    (property "License" "Apache-2.0" (at 96.52 72.39 0)
      (effects (font (size 1.27 1.27) (thickness 0.15)) (justify left bottom) hide)
    )
    (property "Author" "Antmicro" (at 93.98 72.39 0)
      (effects (font (size 1.27 1.27) (thickness 0.15)) (justify left bottom) hide)
    )
    (property "Tolerance" "1%" (at 111.76 72.39 0)
      (effects (font (size 1.27 1.27)) (justify left bottom) hide)
    )
    (property "Public" "False" (at 91.44 72.39 0)
      (effects (font (size 1.27 1.27)) (justify left bottom) hide)
    )
    (pin "1")
    (pin "2")
    (instances
      (project "ecp5-dc-scm"
        (path ""
          (reference "R17") (unit 1)
        )
      )
    )
  )

  (symbol (lib_id "antmicroResistors0402:R_10k_0402") (at 127 52.07 270) (unit 1)
    (in_bom yes) (on_board yes) (dnp no)
    (property "Reference" "R19" (at 128.27 53.34 90)
      (effects (font (size 1.524 1.524)) (justify left))
    )
    (property "Value" "R_10k_0402" (at 123.19 52.07 0)
      (effects (font (size 1.524 1.524)) hide)
    )
    (property "Footprint" "antmicro-footprints:R_0402_1005Metric" (at 132.08 57.15 0)
      (effects (font (size 1.524 1.524)) (justify left) hide)
    )
    (property "Datasheet" "https://www.bourns.com/docs/product-datasheets/cr.pdf" (at 127 52.07 0)
      (effects (font (size 1.27 1.27)) hide)
    )
    (property "Manufacturer" "Bourns" (at 137.16 57.15 0)
      (effects (font (size 1.524 1.524)) (justify left) hide)
    )
    (property "MPN" "CR0402-FX-1002GLF" (at 134.62 57.15 0)
      (effects (font (size 1.524 1.524)) (justify left) hide)
    )
    (property "Val" "10k" (at 128.27 55.88 90)
      (effects (font (size 1.27 1.27)) (justify left))
    )
    (property "License" "Apache-2.0" (at 101.6 72.39 0)
      (effects (font (size 1.27 1.27) (thickness 0.15)) (justify left bottom) hide)
    )
    (property "Author" "Antmicro" (at 99.06 72.39 0)
      (effects (font (size 1.27 1.27) (thickness 0.15)) (justify left bottom) hide)
    )
    (property "Tolerance" "1%" (at 116.84 72.39 0)
      (effects (font (size 1.27 1.27)) (justify left bottom) hide)
    )
    (property "Public" "False" (at 96.52 72.39 0)
      (effects (font (size 1.27 1.27)) (justify left bottom) hide)
    )
    (pin "1")
    (pin "2")
    (instances
      (project "ecp5-dc-scm"
        (path ""
          (reference "R19") (unit 1)
        )
      )
    )
  )

  (symbol (lib_id "antmicroResistors0402:R_10k_0402") (at 175.26 90.17 0) (mirror x) (unit 1)
    (in_bom yes) (on_board yes) (dnp no)
    (property "Reference" "R20" (at 177.8 87.63 0)
      (effects (font (size 1.524 1.524)))
    )
    (property "Value" "R_10k_0402" (at 175.26 86.36 0)
      (effects (font (size 1.524 1.524)) hide)
    )
    (property "Footprint" "antmicro-footprints:R_0402_1005Metric" (at 180.34 95.25 0)
      (effects (font (size 1.524 1.524)) (justify left) hide)
    )
    (property "Datasheet" "https://www.bourns.com/docs/product-datasheets/cr.pdf" (at 175.26 90.17 0)
      (effects (font (size 1.27 1.27)) hide)
    )
    (property "Manufacturer" "Bourns" (at 180.34 100.33 0)
      (effects (font (size 1.524 1.524)) (justify left) hide)
    )
    (property "MPN" "CR0402-FX-1002GLF" (at 180.34 97.79 0)
      (effects (font (size 1.524 1.524)) (justify left) hide)
    )
    (property "Val" "10k" (at 177.8 92.71 0)
      (effects (font (size 1.27 1.27)))
    )
    (property "License" "Apache-2.0" (at 195.58 64.77 0)
      (effects (font (size 1.27 1.27) (thickness 0.15)) (justify left bottom) hide)
    )
    (property "Author" "Antmicro" (at 195.58 62.23 0)
      (effects (font (size 1.27 1.27) (thickness 0.15)) (justify left bottom) hide)
    )
    (property "Tolerance" "1%" (at 195.58 80.01 0)
      (effects (font (size 1.27 1.27)) (justify left bottom) hide)
    )
    (property "Public" "False" (at 195.58 59.69 0)
      (effects (font (size 1.27 1.27)) (justify left bottom) hide)
    )
    (pin "1")
    (pin "2")
    (instances
      (project "ecp5-dc-scm"
        (path ""
          (reference "R20") (unit 1)
        )
      )
    )
  )

  (symbol (lib_id "antmicroResistors0402:R_330R_0402") (at 182.88 118.11 0) (mirror x) (unit 1)
    (in_bom yes) (on_board yes) (dnp no) (fields_autoplaced)
    (property "Reference" "R18" (at 185.42 111.76 0)
      (effects (font (size 1.524 1.524)))
    )
    (property "Value" "R_330R_0402" (at 182.88 114.3 0)
      (effects (font (size 1.524 1.524)) hide)
    )
    (property "Footprint" "antmicro-footprints:R_0402_1005Metric" (at 187.96 123.19 0)
      (effects (font (size 1.524 1.524)) (justify left) hide)
    )
    (property "Datasheet" "https://www.bourns.com/docs/product-datasheets/cr.pdf" (at 182.88 118.11 0)
      (effects (font (size 1.27 1.27)) hide)
    )
    (property "Manufacturer" "Bourns" (at 187.96 128.27 0)
      (effects (font (size 1.524 1.524)) (justify left) hide)
    )
    (property "MPN" "CR0402-FX-3300GLF" (at 187.96 125.73 0)
      (effects (font (size 1.524 1.524)) (justify left) hide)
    )
    (property "Val" "330R" (at 185.42 114.3 0)
      (effects (font (size 1.27 1.27)))
    )
    (property "License" "Apache-2.0" (at 203.2 92.71 0)
      (effects (font (size 1.27 1.27) (thickness 0.15)) (justify left bottom) hide)
    )
    (property "Author" "Antmicro" (at 203.2 90.17 0)
      (effects (font (size 1.27 1.27) (thickness 0.15)) (justify left bottom) hide)
    )
    (property "Tolerance" "1%" (at 203.2 107.95 0)
      (effects (font (size 1.27 1.27)) (justify left bottom) hide)
    )
    (property "Public" "False" (at 203.2 87.63 0)
      (effects (font (size 1.27 1.27)) (justify left bottom) hide)
    )
    (pin "1")
    (pin "2")
    (instances
      (project "ecp5-dc-scm"
        (path ""
          (reference "R18") (unit 1)
        )
      )
    )
  )

  (symbol (lib_id "antmicroCapacitors0402:C_10u_0402") (at 204.47 67.31 90) (unit 1)
    (in_bom yes) (on_board yes) (dnp no) (fields_autoplaced)
    (property "Reference" "C39" (at 201.93 63.4936 90)
      (effects (font (size 1.524 1.524)) (justify left))
    )
    (property "Value" "C_10u_0402" (at 208.28 67.31 0)
      (effects (font (size 1.524 1.524)) hide)
    )
    (property "Footprint" "antmicro-footprints:C_0402_1005Metric" (at 199.39 62.23 0)
      (effects (font (size 1.524 1.524)) (justify left) hide)
    )
    (property "Datasheet" "https://www.yageo.com/en/Chart/Download/pdf/CC0402MRX5R5BB106" (at 204.47 67.31 0)
      (effects (font (size 1.27 1.27)) hide)
    )
    (property "Manufacturer" "YAGEO" (at 194.31 62.23 0)
      (effects (font (size 1.524 1.524)) (justify left) hide)
    )
    (property "MPN" "CC0402MRX5R5BB106" (at 196.85 62.23 0)
      (effects (font (size 1.524 1.524)) (justify left) hide)
    )
    (property "Val" "10u" (at 201.93 66.0336 90)
      (effects (font (size 1.27 1.27)) (justify left))
    )
    (property "License" "Apache-2.0" (at 227.33 46.99 0)
      (effects (font (size 1.27 1.27) (thickness 0.15)) (justify left bottom) hide)
    )
    (property "Author" "Antmicro" (at 229.87 46.99 0)
      (effects (font (size 1.27 1.27) (thickness 0.15)) (justify left bottom) hide)
    )
    (property "Voltage" "" (at 232.41 46.99 0)
      (effects (font (size 1.27 1.27)) (justify left bottom) hide)
    )
    (property "Dielectric" "" (at 234.95 46.99 0)
      (effects (font (size 1.27 1.27)) (justify left bottom) hide)
    )
    (property "Public" "False" (at 237.49 46.99 0)
      (effects (font (size 1.27 1.27)) (justify left bottom) hide)
    )
    (pin "1")
    (pin "2")
    (instances
      (project "ecp5-dc-scm"
        (path ""
          (reference "C39") (unit 1)
        )
      )
    )
  )

  (symbol (lib_id "antmicroCapacitors0402:C_10u_0402") (at 213.36 67.31 90) (unit 1)
    (in_bom yes) (on_board yes) (dnp no) (fields_autoplaced)
    (property "Reference" "C40" (at 210.82 63.4936 90)
      (effects (font (size 1.524 1.524)) (justify left))
    )
    (property "Value" "C_10u_0402" (at 217.17 67.31 0)
      (effects (font (size 1.524 1.524)) hide)
    )
    (property "Footprint" "antmicro-footprints:C_0402_1005Metric" (at 208.28 62.23 0)
      (effects (font (size 1.524 1.524)) (justify left) hide)
    )
    (property "Datasheet" "https://www.yageo.com/en/Chart/Download/pdf/CC0402MRX5R5BB106" (at 213.36 67.31 0)
      (effects (font (size 1.27 1.27)) hide)
    )
    (property "Manufacturer" "YAGEO" (at 203.2 62.23 0)
      (effects (font (size 1.524 1.524)) (justify left) hide)
    )
    (property "MPN" "CC0402MRX5R5BB106" (at 205.74 62.23 0)
      (effects (font (size 1.524 1.524)) (justify left) hide)
    )
    (property "Val" "10u" (at 210.82 66.0336 90)
      (effects (font (size 1.27 1.27)) (justify left))
    )
    (property "License" "Apache-2.0" (at 236.22 46.99 0)
      (effects (font (size 1.27 1.27) (thickness 0.15)) (justify left bottom) hide)
    )
    (property "Author" "Antmicro" (at 238.76 46.99 0)
      (effects (font (size 1.27 1.27) (thickness 0.15)) (justify left bottom) hide)
    )
    (property "Voltage" "" (at 241.3 46.99 0)
      (effects (font (size 1.27 1.27)) (justify left bottom) hide)
    )
    (property "Dielectric" "" (at 243.84 46.99 0)
      (effects (font (size 1.27 1.27)) (justify left bottom) hide)
    )
    (property "Public" "False" (at 246.38 46.99 0)
      (effects (font (size 1.27 1.27)) (justify left bottom) hide)
    )
    (pin "1")
    (pin "2")
    (instances
      (project "ecp5-dc-scm"
        (path ""
          (reference "C40") (unit 1)
        )
      )
    )
  )

  (symbol (lib_id "antmicroCapacitors0402:C_10u_0402") (at 222.25 67.31 90) (unit 1)
    (in_bom yes) (on_board yes) (dnp no) (fields_autoplaced)
    (property "Reference" "C41" (at 219.71 63.4936 90)
      (effects (font (size 1.524 1.524)) (justify left))
    )
    (property "Value" "C_10u_0402" (at 226.06 67.31 0)
      (effects (font (size 1.524 1.524)) hide)
    )
    (property "Footprint" "antmicro-footprints:C_0402_1005Metric" (at 217.17 62.23 0)
      (effects (font (size 1.524 1.524)) (justify left) hide)
    )
    (property "Datasheet" "https://www.yageo.com/en/Chart/Download/pdf/CC0402MRX5R5BB106" (at 222.25 67.31 0)
      (effects (font (size 1.27 1.27)) hide)
    )
    (property "Manufacturer" "YAGEO" (at 212.09 62.23 0)
      (effects (font (size 1.524 1.524)) (justify left) hide)
    )
    (property "MPN" "CC0402MRX5R5BB106" (at 214.63 62.23 0)
      (effects (font (size 1.524 1.524)) (justify left) hide)
    )
    (property "Val" "10u" (at 219.71 66.0336 90)
      (effects (font (size 1.27 1.27)) (justify left))
    )
    (property "License" "Apache-2.0" (at 245.11 46.99 0)
      (effects (font (size 1.27 1.27) (thickness 0.15)) (justify left bottom) hide)
    )
    (property "Author" "Antmicro" (at 247.65 46.99 0)
      (effects (font (size 1.27 1.27) (thickness 0.15)) (justify left bottom) hide)
    )
    (property "Voltage" "" (at 250.19 46.99 0)
      (effects (font (size 1.27 1.27)) (justify left bottom) hide)
    )
    (property "Dielectric" "" (at 252.73 46.99 0)
      (effects (font (size 1.27 1.27)) (justify left bottom) hide)
    )
    (property "Public" "False" (at 255.27 46.99 0)
      (effects (font (size 1.27 1.27)) (justify left bottom) hide)
    )
    (pin "1")
    (pin "2")
    (instances
      (project "ecp5-dc-scm"
        (path ""
          (reference "C41") (unit 1)
        )
      )
    )
  )

  (symbol (lib_id "antmicroCapacitors0402:C_10u_0402") (at 231.14 67.31 90) (unit 1)
    (in_bom yes) (on_board yes) (dnp no)
    (property "Reference" "C42" (at 224.79 63.5 90)
      (effects (font (size 1.524 1.524)) (justify right))
    )
    (property "Value" "C_10u_0402" (at 234.95 67.31 0)
      (effects (font (size 1.524 1.524)) hide)
    )
    (property "Footprint" "antmicro-footprints:C_0402_1005Metric" (at 226.06 62.23 0)
      (effects (font (size 1.524 1.524)) (justify left) hide)
    )
    (property "Datasheet" "https://www.yageo.com/en/Chart/Download/pdf/CC0402MRX5R5BB106" (at 231.14 67.31 0)
      (effects (font (size 1.27 1.27)) hide)
    )
    (property "Manufacturer" "YAGEO" (at 220.98 62.23 0)
      (effects (font (size 1.524 1.524)) (justify left) hide)
    )
    (property "MPN" "CC0402MRX5R5BB106" (at 223.52 62.23 0)
      (effects (font (size 1.524 1.524)) (justify left) hide)
    )
    (property "Val" "10u" (at 226.06 66.04 90)
      (effects (font (size 1.27 1.27)) (justify right))
    )
    (property "License" "Apache-2.0" (at 254 46.99 0)
      (effects (font (size 1.27 1.27) (thickness 0.15)) (justify left bottom) hide)
    )
    (property "Author" "Antmicro" (at 256.54 46.99 0)
      (effects (font (size 1.27 1.27) (thickness 0.15)) (justify left bottom) hide)
    )
    (property "Voltage" "" (at 259.08 46.99 0)
      (effects (font (size 1.27 1.27)) (justify left bottom) hide)
    )
    (property "Dielectric" "" (at 261.62 46.99 0)
      (effects (font (size 1.27 1.27)) (justify left bottom) hide)
    )
    (property "Public" "False" (at 264.16 46.99 0)
      (effects (font (size 1.27 1.27)) (justify left bottom) hide)
    )
    (pin "1")
    (pin "2")
    (instances
      (project "ecp5-dc-scm"
        (path ""
          (reference "C42") (unit 1)
        )
      )
    )
  )

  (symbol (lib_id "antmicropower:GND") (at 173.99 143.51 0) (unit 1)
    (in_bom yes) (on_board yes) (dnp no)
    (property "Reference" "#PWR012" (at 173.99 149.86 0)
      (effects (font (size 1.27 1.27)) hide)
    )
    (property "Value" "GND" (at 174.117 147.9042 0)
      (effects (font (size 1.27 1.27)))
    )
    (property "Footprint" "" (at 173.99 143.51 0)
      (effects (font (size 1.27 1.27)) hide)
    )
    (property "Datasheet" "" (at 173.99 143.51 0)
      (effects (font (size 1.27 1.27)) hide)
    )
    (property "Author" "Antmicro" (at 182.88 151.13 0)
      (effects (font (size 1.27 1.27) (thickness 0.15)) (justify left bottom) hide)
    )
    (property "License" "Apache-2.0" (at 182.88 153.67 0)
      (effects (font (size 1.27 1.27) (thickness 0.15)) (justify left bottom) hide)
    )
    (pin "1")
    (instances
      (project "ecp5-dc-scm"
        (path ""
          (reference "#PWR012") (unit 1)
        )
      )
    )
  )

  (symbol (lib_id "antmicropower:GND") (at 213.36 68.58 0) (unit 1)
    (in_bom yes) (on_board yes) (dnp no)
    (property "Reference" "#PWR013" (at 213.36 74.93 0)
      (effects (font (size 1.27 1.27)) hide)
    )
    (property "Value" "GND" (at 213.487 72.9742 0)
      (effects (font (size 1.27 1.27)))
    )
    (property "Footprint" "" (at 213.36 68.58 0)
      (effects (font (size 1.27 1.27)) hide)
    )
    (property "Datasheet" "" (at 213.36 68.58 0)
      (effects (font (size 1.27 1.27)) hide)
    )
    (property "Author" "Antmicro" (at 222.25 76.2 0)
      (effects (font (size 1.27 1.27) (thickness 0.15)) (justify left bottom) hide)
    )
    (property "License" "Apache-2.0" (at 222.25 78.74 0)
      (effects (font (size 1.27 1.27) (thickness 0.15)) (justify left bottom) hide)
    )
    (pin "1")
    (instances
      (project "ecp5-dc-scm"
        (path ""
          (reference "#PWR013") (unit 1)
        )
      )
    )
  )

  (symbol (lib_id "antmicropower:GND") (at 222.25 68.58 0) (unit 1)
    (in_bom yes) (on_board yes) (dnp no)
    (property "Reference" "#PWR014" (at 222.25 74.93 0)
      (effects (font (size 1.27 1.27)) hide)
    )
    (property "Value" "GND" (at 222.377 72.9742 0)
      (effects (font (size 1.27 1.27)))
    )
    (property "Footprint" "" (at 222.25 68.58 0)
      (effects (font (size 1.27 1.27)) hide)
    )
    (property "Datasheet" "" (at 222.25 68.58 0)
      (effects (font (size 1.27 1.27)) hide)
    )
    (property "Author" "Antmicro" (at 231.14 76.2 0)
      (effects (font (size 1.27 1.27) (thickness 0.15)) (justify left bottom) hide)
    )
    (property "License" "Apache-2.0" (at 231.14 78.74 0)
      (effects (font (size 1.27 1.27) (thickness 0.15)) (justify left bottom) hide)
    )
    (pin "1")
    (instances
      (project "ecp5-dc-scm"
        (path ""
          (reference "#PWR014") (unit 1)
        )
      )
    )
  )

  (symbol (lib_id "antmicropower:GND") (at 231.14 68.58 0) (unit 1)
    (in_bom yes) (on_board yes) (dnp no)
    (property "Reference" "#PWR015" (at 231.14 74.93 0)
      (effects (font (size 1.27 1.27)) hide)
    )
    (property "Value" "GND" (at 231.267 72.9742 0)
      (effects (font (size 1.27 1.27)))
    )
    (property "Footprint" "" (at 231.14 68.58 0)
      (effects (font (size 1.27 1.27)) hide)
    )
    (property "Datasheet" "" (at 231.14 68.58 0)
      (effects (font (size 1.27 1.27)) hide)
    )
    (property "Author" "Antmicro" (at 240.03 76.2 0)
      (effects (font (size 1.27 1.27) (thickness 0.15)) (justify left bottom) hide)
    )
    (property "License" "Apache-2.0" (at 240.03 78.74 0)
      (effects (font (size 1.27 1.27) (thickness 0.15)) (justify left bottom) hide)
    )
    (pin "1")
    (instances
      (project "ecp5-dc-scm"
        (path ""
          (reference "#PWR015") (unit 1)
        )
      )
    )
  )

  (symbol (lib_id "antmicroCapacitors0402:C_100n_0402") (at 134.62 115.57 180) (unit 1)
    (in_bom yes) (on_board yes) (dnp no)
    (property "Reference" "C33" (at 135.89 114.3 0)
      (effects (font (size 1.524 1.524)))
    )
    (property "Value" "C_100n_0402" (at 134.62 111.76 0)
      (effects (font (size 1.524 1.524)) hide)
    )
    (property "Footprint" "antmicro-footprints:C_0402_1005Metric" (at 129.54 120.65 0)
      (effects (font (size 1.524 1.524)) (justify left) hide)
    )
    (property "Datasheet" "https://www.murata.com/products/productdetail?partno=GRM155R61H104KE14%23" (at 134.62 115.57 0)
      (effects (font (size 1.27 1.27)) hide)
    )
    (property "Manufacturer" "Murata" (at 129.54 125.73 0)
      (effects (font (size 1.524 1.524)) (justify left) hide)
    )
    (property "MPN" "GRM155R61H104KE14D" (at 129.54 123.19 0)
      (effects (font (size 1.524 1.524)) (justify left) hide)
    )
    (property "Val" "100n" (at 128.27 114.3 0)
      (effects (font (size 1.27 1.27)))
    )
    (property "License" "Apache-2.0" (at 114.3 92.71 0)
      (effects (font (size 1.27 1.27) (thickness 0.15)) (justify left bottom) hide)
    )
    (property "Author" "Antmicro" (at 114.3 90.17 0)
      (effects (font (size 1.27 1.27) (thickness 0.15)) (justify left bottom) hide)
    )
    (property "Voltage" "50V" (at 114.3 87.63 0)
      (effects (font (size 1.27 1.27)) (justify left bottom) hide)
    )
    (property "Dielectric" "X5R" (at 114.3 85.09 0)
      (effects (font (size 1.27 1.27)) (justify left bottom) hide)
    )
    (property "Public" "False" (at 114.3 82.55 0)
      (effects (font (size 1.27 1.27)) (justify left bottom) hide)
    )
    (pin "1")
    (pin "2")
    (instances
      (project "ecp5-dc-scm"
        (path ""
          (reference "C33") (unit 1)
        )
      )
    )
  )

  (symbol (lib_id "antmicroCapacitors0402:C_100n_0402") (at 127 118.11 180) (unit 1)
    (in_bom yes) (on_board yes) (dnp no)
    (property "Reference" "C37" (at 128.27 119.38 0)
      (effects (font (size 1.524 1.524)))
    )
    (property "Value" "C_100n_0402" (at 127 114.3 0)
      (effects (font (size 1.524 1.524)) hide)
    )
    (property "Footprint" "antmicro-footprints:C_0402_1005Metric" (at 121.92 123.19 0)
      (effects (font (size 1.524 1.524)) (justify left) hide)
    )
    (property "Datasheet" "https://www.murata.com/products/productdetail?partno=GRM155R61H104KE14%23" (at 127 118.11 0)
      (effects (font (size 1.27 1.27)) hide)
    )
    (property "Manufacturer" "Murata" (at 121.92 128.27 0)
      (effects (font (size 1.524 1.524)) (justify left) hide)
    )
    (property "MPN" "GRM155R61H104KE14D" (at 121.92 125.73 0)
      (effects (font (size 1.524 1.524)) (justify left) hide)
    )
    (property "Val" "100n" (at 120.65 119.38 0)
      (effects (font (size 1.27 1.27)))
    )
    (property "License" "Apache-2.0" (at 106.68 95.25 0)
      (effects (font (size 1.27 1.27) (thickness 0.15)) (justify left bottom) hide)
    )
    (property "Author" "Antmicro" (at 106.68 92.71 0)
      (effects (font (size 1.27 1.27) (thickness 0.15)) (justify left bottom) hide)
    )
    (property "Voltage" "50V" (at 106.68 90.17 0)
      (effects (font (size 1.27 1.27)) (justify left bottom) hide)
    )
    (property "Dielectric" "X5R" (at 106.68 87.63 0)
      (effects (font (size 1.27 1.27)) (justify left bottom) hide)
    )
    (property "Public" "False" (at 106.68 85.09 0)
      (effects (font (size 1.27 1.27)) (justify left bottom) hide)
    )
    (pin "1")
    (pin "2")
    (instances
      (project "ecp5-dc-scm"
        (path ""
          (reference "C37") (unit 1)
        )
      )
    )
  )

  (symbol (lib_id "antmicroCapacitors0402:C_100n_0402") (at 134.62 130.81 180) (unit 1)
    (in_bom yes) (on_board yes) (dnp no)
    (property "Reference" "C34" (at 135.89 129.54 0)
      (effects (font (size 1.524 1.524)))
    )
    (property "Value" "C_100n_0402" (at 134.62 127 0)
      (effects (font (size 1.524 1.524)) hide)
    )
    (property "Footprint" "antmicro-footprints:C_0402_1005Metric" (at 129.54 135.89 0)
      (effects (font (size 1.524 1.524)) (justify left) hide)
    )
    (property "Datasheet" "https://www.murata.com/products/productdetail?partno=GRM155R61H104KE14%23" (at 134.62 130.81 0)
      (effects (font (size 1.27 1.27)) hide)
    )
    (property "Manufacturer" "Murata" (at 129.54 140.97 0)
      (effects (font (size 1.524 1.524)) (justify left) hide)
    )
    (property "MPN" "GRM155R61H104KE14D" (at 129.54 138.43 0)
      (effects (font (size 1.524 1.524)) (justify left) hide)
    )
    (property "Val" "100n" (at 128.27 129.54 0)
      (effects (font (size 1.27 1.27)))
    )
    (property "License" "Apache-2.0" (at 114.3 107.95 0)
      (effects (font (size 1.27 1.27) (thickness 0.15)) (justify left bottom) hide)
    )
    (property "Author" "Antmicro" (at 114.3 105.41 0)
      (effects (font (size 1.27 1.27) (thickness 0.15)) (justify left bottom) hide)
    )
    (property "Voltage" "50V" (at 114.3 102.87 0)
      (effects (font (size 1.27 1.27)) (justify left bottom) hide)
    )
    (property "Dielectric" "X5R" (at 114.3 100.33 0)
      (effects (font (size 1.27 1.27)) (justify left bottom) hide)
    )
    (property "Public" "False" (at 114.3 97.79 0)
      (effects (font (size 1.27 1.27)) (justify left bottom) hide)
    )
    (pin "1")
    (pin "2")
    (instances
      (project "ecp5-dc-scm"
        (path ""
          (reference "C34") (unit 1)
        )
      )
    )
  )

  (symbol (lib_id "antmicroCapacitors0402:C_100n_0402") (at 127 133.35 180) (unit 1)
    (in_bom yes) (on_board yes) (dnp no)
    (property "Reference" "C38" (at 128.27 134.62 0)
      (effects (font (size 1.524 1.524)))
    )
    (property "Value" "C_100n_0402" (at 127 129.54 0)
      (effects (font (size 1.524 1.524)) hide)
    )
    (property "Footprint" "antmicro-footprints:C_0402_1005Metric" (at 121.92 138.43 0)
      (effects (font (size 1.524 1.524)) (justify left) hide)
    )
    (property "Datasheet" "https://www.murata.com/products/productdetail?partno=GRM155R61H104KE14%23" (at 127 133.35 0)
      (effects (font (size 1.27 1.27)) hide)
    )
    (property "Manufacturer" "Murata" (at 121.92 143.51 0)
      (effects (font (size 1.524 1.524)) (justify left) hide)
    )
    (property "MPN" "GRM155R61H104KE14D" (at 121.92 140.97 0)
      (effects (font (size 1.524 1.524)) (justify left) hide)
    )
    (property "Val" "100n" (at 120.65 134.62 0)
      (effects (font (size 1.27 1.27)))
    )
    (property "License" "Apache-2.0" (at 106.68 110.49 0)
      (effects (font (size 1.27 1.27) (thickness 0.15)) (justify left bottom) hide)
    )
    (property "Author" "Antmicro" (at 106.68 107.95 0)
      (effects (font (size 1.27 1.27) (thickness 0.15)) (justify left bottom) hide)
    )
    (property "Voltage" "50V" (at 106.68 105.41 0)
      (effects (font (size 1.27 1.27)) (justify left bottom) hide)
    )
    (property "Dielectric" "X5R" (at 106.68 102.87 0)
      (effects (font (size 1.27 1.27)) (justify left bottom) hide)
    )
    (property "Public" "False" (at 106.68 100.33 0)
      (effects (font (size 1.27 1.27)) (justify left bottom) hide)
    )
    (pin "1")
    (pin "2")
    (instances
      (project "ecp5-dc-scm"
        (path ""
          (reference "C38") (unit 1)
        )
      )
    )
  )

  (symbol (lib_name "LED_G_0603_LG_L29K-G2J1-24-Z_1") (lib_id "antmicroLEDIndicationDiscrete:LED_G_0603_LG_L29K-G2J1-24-Z") (at 175.26 118.11 0) (mirror x) (unit 1)
    (in_bom yes) (on_board yes) (dnp no)
    (property "Reference" "D1" (at 177.8 115.57 0)
      (effects (font (size 1.27 1.27) (thickness 0.15)))
    )
    (property "Value" "LED_G_0603_LG_L29K-G2J1-24-Z" (at 195.58 110.49 0)
      (effects (font (size 1.27 1.27) (thickness 0.15)) (justify left bottom) hide)
    )
    (property "Footprint" "antmicro-footprints:LED_0603_1608Metric_G" (at 195.58 107.95 0)
      (effects (font (size 1.27 1.27) (thickness 0.15)) (justify left bottom) hide)
    )
    (property "Datasheet" "https://look.ams-osram.com/m/19ee86b3ae0ee95b/original/LG-L29K.pdf" (at 195.58 105.41 0)
      (effects (font (size 1.27 1.27) (thickness 0.15)) (justify left bottom) hide)
    )
    (property "MPN" "LG L29K-G2J1-24-Z" (at 195.58 102.87 0)
      (effects (font (size 1.27 1.27) (thickness 0.15)) (justify left bottom) hide)
    )
    (property "Manufacturer" "OSRAM" (at 195.58 100.33 0)
      (effects (font (size 1.27 1.27) (thickness 0.15)) (justify left bottom) hide)
    )
    (property "Color" "Green" (at 177.8 121.92 0)
      (effects (font (size 1.27 1.27)))
    )
    (property "Author" "Antmicro" (at 195.58 97.79 0)
      (effects (font (size 1.27 1.27) (thickness 0.15)) (justify left bottom) hide)
    )
    (property "License" "Apache-2.0" (at 195.58 95.25 0)
      (effects (font (size 1.27 1.27) (thickness 0.15)) (justify left bottom) hide)
    )
    (pin "1")
    (pin "2")
    (instances
      (project "ecp5-dc-scm"
        (path ""
          (reference "D1") (unit 1)
        )
      )
    )
  )

  (symbol (lib_id "antmicroTestPoints:TP_1mm_SMD") (at 116.84 66.04 180) (unit 1)
    (in_bom no) (on_board yes) (dnp no)
    (property "Reference" "TP2" (at 110.49 66.04 0)
      (effects (font (size 1.27 1.27) (thickness 0.15)))
    )
    (property "Value" "TP_1mm_SMD" (at 101.6 58.42 0)
      (effects (font (size 1.27 1.27) (thickness 0.15)) (justify left bottom) hide)
    )
    (property "Footprint" "antmicro-footprints:TP_SMD_1mm" (at 101.6 55.88 0)
      (effects (font (size 1.27 1.27) (thickness 0.15)) (justify left bottom) hide)
    )
    (property "Datasheet" "" (at 99.06 53.34 0)
      (effects (font (size 1.27 1.27) (thickness 0.15)) (justify left bottom) hide)
    )
    (property "MPN" "" (at 116.84 66.04 0)
      (effects (font (size 1.27 1.27)) hide)
    )
    (property "Manufacturer" "" (at 116.84 66.04 0)
      (effects (font (size 1.27 1.27)) hide)
    )
    (property "Author" "Antmicro" (at 101.6 50.8 0)
      (effects (font (size 1.27 1.27) (thickness 0.15)) (justify left bottom) hide)
    )
    (property "License" "Apache-2.0" (at 101.6 48.26 0)
      (effects (font (size 1.27 1.27) (thickness 0.15)) (justify left bottom) hide)
    )
    (pin "1")
    (instances
      (project "ecp5-dc-scm"
        (path ""
          (reference "TP2") (unit 1)
        )
      )
    )
  )

  (symbol (lib_id "antmicroMechanicalParts:Spacer_Drill3.7mm_H2.5mm_9774025151R") (at 193.04 140.97 0) (unit 1)
    (in_bom yes) (on_board yes) (dnp no) (fields_autoplaced)
    (property "Reference" "H1" (at 201.93 139.7 0)
      (effects (font (size 1.27 1.27) (thickness 0.15)) (justify left))
    )
    (property "Value" "Spacer_Drill3.7mm_H2.5mm_9774025151R" (at 201.93 142.24 0)
      (effects (font (size 1.27 1.27) (thickness 0.15)) (justify left))
    )
    (property "Footprint" "antmicro-footprints:Spacer_Drill3.7mm_H2.5mm_9774025151R" (at 215.9 148.59 0)
      (effects (font (size 1.27 1.27) (thickness 0.15)) (justify left bottom) hide)
    )
    (property "Datasheet" "https://www.we-online.com/components/products/datasheet/9774025151R.pdf" (at 215.9 151.13 0)
      (effects (font (size 1.27 1.27) (thickness 0.15)) (justify left bottom) hide)
    )
    (property "Manufacturer" "Würth Elektronik" (at 215.9 153.67 0)
      (effects (font (size 1.27 1.27) (thickness 0.15)) (justify left bottom) hide)
    )
    (property "MPN" "9774025151R" (at 215.9 156.21 0)
      (effects (font (size 1.27 1.27) (thickness 0.15)) (justify left bottom) hide)
    )
    (property "Author" "Antmicro" (at 215.9 158.75 0)
      (effects (font (size 1.27 1.27) (thickness 0.15)) (justify left bottom) hide)
    )
    (property "Public" "False" (at 215.9 153.67 0)
      (effects (font (size 1.27 1.27)) (justify left bottom) hide)
    )
    (property "License" "Apache-2.0" (at 215.9 161.29 0)
      (effects (font (size 1.27 1.27) (thickness 0.15)) (justify left bottom) hide)
    )
    (pin "1")
    (instances
      (project "ecp5-dc-scm"
        (path ""
          (reference "H1") (unit 1)
        )
      )
    )
  )

  (symbol (lib_id "antmicroTestPoints:TP_1mm_SMD") (at 116.84 68.58 180) (unit 1)
    (in_bom no) (on_board yes) (dnp no)
    (property "Reference" "TP1" (at 110.49 68.58 0)
      (effects (font (size 1.27 1.27) (thickness 0.15)))
    )
    (property "Value" "TP_1mm_SMD" (at 101.6 60.96 0)
      (effects (font (size 1.27 1.27) (thickness 0.15)) (justify left bottom) hide)
    )
    (property "Footprint" "antmicro-footprints:TP_SMD_1mm" (at 101.6 58.42 0)
      (effects (font (size 1.27 1.27) (thickness 0.15)) (justify left bottom) hide)
    )
    (property "Datasheet" "" (at 99.06 55.88 0)
      (effects (font (size 1.27 1.27) (thickness 0.15)) (justify left bottom) hide)
    )
    (property "MPN" "" (at 116.84 68.58 0)
      (effects (font (size 1.27 1.27)) hide)
    )
    (property "Manufacturer" "" (at 116.84 68.58 0)
      (effects (font (size 1.27 1.27)) hide)
    )
    (property "Author" "Antmicro" (at 101.6 53.34 0)
      (effects (font (size 1.27 1.27) (thickness 0.15)) (justify left bottom) hide)
    )
    (property "License" "Apache-2.0" (at 101.6 50.8 0)
      (effects (font (size 1.27 1.27) (thickness 0.15)) (justify left bottom) hide)
    )
    (pin "1")
    (instances
      (project "ecp5-dc-scm"
        (path ""
          (reference "TP1") (unit 1)
        )
      )
    )
  )

  (symbol (lib_id "antmicroTestPoints:TP_1mm_SMD") (at 119.38 62.23 90) (unit 1)
    (in_bom no) (on_board yes) (dnp no)
    (property "Reference" "TP3" (at 116.84 58.42 90)
      (effects (font (size 1.27 1.27) (thickness 0.15)))
    )
    (property "Value" "TP_1mm_SMD" (at 127 46.99 0)
      (effects (font (size 1.27 1.27) (thickness 0.15)) (justify left bottom) hide)
    )
    (property "Footprint" "antmicro-footprints:TP_SMD_1mm" (at 129.54 46.99 0)
      (effects (font (size 1.27 1.27) (thickness 0.15)) (justify left bottom) hide)
    )
    (property "Datasheet" "" (at 132.08 44.45 0)
      (effects (font (size 1.27 1.27) (thickness 0.15)) (justify left bottom) hide)
    )
    (property "MPN" "" (at 119.38 62.23 0)
      (effects (font (size 1.27 1.27)) hide)
    )
    (property "Manufacturer" "" (at 119.38 62.23 0)
      (effects (font (size 1.27 1.27)) hide)
    )
    (property "Author" "Antmicro" (at 134.62 46.99 0)
      (effects (font (size 1.27 1.27) (thickness 0.15)) (justify left bottom) hide)
    )
    (property "License" "Apache-2.0" (at 137.16 46.99 0)
      (effects (font (size 1.27 1.27) (thickness 0.15)) (justify left bottom) hide)
    )
    (pin "1")
    (instances
      (project "ecp5-dc-scm"
        (path ""
          (reference "TP3") (unit 1)
        )
      )
    )
  )

  (symbol (lib_id "antmicropower:GND") (at 204.47 68.58 0) (unit 1)
    (in_bom yes) (on_board yes) (dnp no)
    (property "Reference" "#PWR011" (at 204.47 74.93 0)
      (effects (font (size 1.27 1.27)) hide)
    )
    (property "Value" "GND" (at 204.597 72.9742 0)
      (effects (font (size 1.27 1.27)))
    )
    (property "Footprint" "" (at 204.47 68.58 0)
      (effects (font (size 1.27 1.27)) hide)
    )
    (property "Datasheet" "" (at 204.47 68.58 0)
      (effects (font (size 1.27 1.27)) hide)
    )
    (property "Author" "Antmicro" (at 213.36 76.2 0)
      (effects (font (size 1.27 1.27) (thickness 0.15)) (justify left bottom) hide)
    )
    (property "License" "Apache-2.0" (at 213.36 78.74 0)
      (effects (font (size 1.27 1.27) (thickness 0.15)) (justify left bottom) hide)
    )
    (pin "1")
    (instances
      (project "ecp5-dc-scm"
        (path ""
          (reference "#PWR011") (unit 1)
        )
      )
    )
  )
)
